# BASEBOARD_FAB2 (Tioga Pass) — schematic netlist excerpt (pin names and nets, part order shuffled) for the footprints in the layout excerpt that follows; sources: Cadence DE-HDL packaged netlist, KiCad conversion of Wiwynn_Tioga_Pass_MB.brd

R8B4  RES  100.0K 1% CHIP  pkg 0402  page 198 : A = FM_CTNR_PS_ON ; B = GND
R3D32  RES  10.0 1% EMPTY  pkg 0402  page 71 : A = PVCCIO_CPU1 ; B = VSENSE_PMAX_CPU1

(kicad_pcb
	(version 20260206)
	(generator "pcbnew")
	(generator_version "10.0")
	(general
		(thickness 1.6)
		(legacy_teardrops no)
	)
	(paper "A4")
	(title_block
		(title "Wiwynn_Tioga_Pass_MB.brd")
		(comment 1 "Tioga Pass / footprints 2165-2166 of 4770")
	)
	(layers
		(0 "F.Cu" signal "TOP")
		(4 "In1.Cu" signal "L2GND")
		(6 "In2.Cu" signal "L3")
		(8 "In3.Cu" signal "L4GND")
		(10 "In4.Cu" signal "L5")
		(12 "In5.Cu" signal "L6GND")
		(14 "In6.Cu" signal "L7VCC")
		(16 "In7.Cu" signal "L8VCC")
		(18 "In8.Cu" signal "L9GND")
		(20 "In9.Cu" signal "L10")
		(22 "In10.Cu" signal "L11GND")
		(24 "In11.Cu" signal "L12")
		(26 "In12.Cu" signal "L13GND")
		(2 "B.Cu" signal "BOTTOM")
		(9 "F.Adhes" user "F.Adhesive")
		(11 "B.Adhes" user "B.Adhesive")
		(13 "F.Paste" user "Package Geometry/Pastemask Top")
		(15 "B.Paste" user "Package Geometry/Pastemask Bottom")
		(5 "F.SilkS" user "Ref Des/Silkscreen Top")
		(7 "B.SilkS" user "Ref Des/Silkscreen Bottom")
		(1 "F.Mask" user "Board Geometry/Soldermask Top")
		(3 "B.Mask" user "Board Geometry/Soldermask Bottom")
		(17 "Dwgs.User" user "User.Drawings")
		(19 "Cmts.User" user "User.Comments")
		(21 "Eco1.User" user "User.Eco1")
		(23 "Eco2.User" user "User.Eco2")
		(25 "Edge.Cuts" user "Board Geometry/Outline")
		(27 "Margin" user)
		(31 "F.CrtYd" user "Package Geometry/Place Bound Top")
		(29 "B.CrtYd" user "Package Geometry/Place Bound Bottom")
		(35 "F.Fab" user "Ref Des/Assembly Top")
		(33 "B.Fab" user "Ref Des/Assembly Bottom")
	)
	(footprint ""
		(layer "F.Cu")
		(at 430.026826 -131.636008)
		(property "Reference" "R8B4"
			(at 0 0 0)
			(layer "F.SilkS")
			(hide yes)
			(effects
				(font
					(size 1.27 1.27)
				)
			)
		)
		(property "Value" ""
			(at 0 0 0)
			(layer "F.Fab")
			(effects
				(font
					(size 1.27 1.27)
				)
			)
		)
		(duplicate_pad_numbers_are_jumpers no)
		(fp_poly
			(pts
				(xy -0.2794 -0.1016) (xy 0.2794 -0.1016) (xy 0.2794 0.9906) (xy -0.2794 0.9906)
			)
			(stroke
				(width 0)
				(type default)
			)
			(fill no)
			(layer "F.CrtYd")
		)
		(fp_line
			(start -0.2794 -0.1016)
			(end -0.2794 0.9906)
			(stroke
				(width 0.1)
				(type default)
			)
			(layer "F.Fab")
		)
		(fp_line
			(start -0.2794 0.9906)
			(end 0.2794 0.9906)
			(stroke
				(width 0.1)
				(type default)
			)
			(layer "F.Fab")
		)
		(fp_line
			(start 0.2794 -0.1016)
			(end -0.2794 -0.1016)
			(stroke
				(width 0.1)
				(type default)
			)
			(layer "F.Fab")
		)
		(fp_line
			(start 0.2794 0.9906)
			(end 0.2794 -0.1016)
			(stroke
				(width 0.1)
				(type default)
			)
			(layer "F.Fab")
		)
		(pad "1" smd rect
			(at 0 0)
			(size 0.508 0.508)
			(layers "F.Cu" "F.Mask" "F.Paste")
			(net "FM_CTNR_PS_ON")
		)
		(pad "2" smd rect
			(at 0 0.889)
			(size 0.508 0.508)
			(layers "F.Cu" "F.Mask" "F.Paste")
			(net "GND")
		)
		(zone
			(layer "F.Cu")
			(hatch none 0.5)
			(connect_pads
				(clearance 0)
			)
			(min_thickness 0.25)
			(keepout
				(tracks allowed)
				(vias not_allowed)
				(pads allowed)
				(copperpour not_allowed)
				(footprints allowed)
			)
			(placement
				(enabled no)
				(sheetname "")
			)
			(fill
				(thermal_gap 0.5)
				(thermal_bridge_width 0.5)
				(island_removal_mode 0)
			)
			(polygon
				(pts
					(xy 429.772826 -131.382008) (xy 430.280826 -131.382008) (xy 430.280826 -131.001008) (xy 429.772826 -131.001008)
				)
			)
		)
		(zone
			(layer "F.Cu")
			(hatch none 0.5)
			(connect_pads
				(clearance 0)
			)
			(min_thickness 0.25)
			(keepout
				(tracks not_allowed)
				(vias allowed)
				(pads allowed)
				(copperpour not_allowed)
				(footprints allowed)
			)
			(placement
				(enabled no)
				(sheetname "")
			)
			(fill
				(thermal_gap 0.5)
				(thermal_bridge_width 0.5)
				(island_removal_mode 0)
			)
			(polygon
				(pts
					(xy 429.772826 -131.001008) (xy 430.280826 -131.001008) (xy 430.280826 -131.382008) (xy 429.772826 -131.382008)
				)
			)
		)
	)
	(footprint ""
		(layer "F.Cu")
		(at 108.712 -69.85)
		(property "Reference" "R3D32"
			(at 0 0 0)
			(layer "F.SilkS")
			(hide yes)
			(effects
				(font
					(size 1.27 1.27)
				)
			)
		)
		(property "Value" ""
			(at 0 0 0)
			(layer "F.Fab")
			(effects
				(font
					(size 1.27 1.27)
				)
			)
		)
		(duplicate_pad_numbers_are_jumpers no)
		(fp_poly
			(pts
				(xy -0.2794 -0.1016) (xy 0.2794 -0.1016) (xy 0.2794 0.9906) (xy -0.2794 0.9906)
			)
			(stroke
				(width 0)
				(type default)
			)
			(fill no)
			(layer "F.CrtYd")
		)
		(fp_line
			(start -0.2794 -0.1016)
			(end -0.2794 0.9906)
			(stroke
				(width 0.1)
				(type default)
			)
			(layer "F.Fab")
		)
		(fp_line
			(start -0.2794 0.9906)
			(end 0.2794 0.9906)
			(stroke
				(width 0.1)
				(type default)
			)
			(layer "F.Fab")
		)
		(fp_line
			(start 0.2794 -0.1016)
			(end -0.2794 -0.1016)
			(stroke
				(width 0.1)
				(type default)
			)
			(layer "F.Fab")
		)
		(fp_line
			(start 0.2794 0.9906)
			(end 0.2794 -0.1016)
			(stroke
				(width 0.1)
				(type default)
			)
			(layer "F.Fab")
		)
		(pad "1" smd rect
			(at 0 0)
			(size 0.508 0.508)
			(layers "F.Cu" "F.Mask" "F.Paste")
			(net "PVCCIO_CPU1")
		)
		(pad "2" smd rect
			(at 0 0.889)
			(size 0.508 0.508)
			(layers "F.Cu" "F.Mask" "F.Paste")
			(net "VSENSE_PMAX_CPU1")
		)
		(zone
			(layer "F.Cu")
			(hatch none 0.5)
			(connect_pads
				(clearance 0)
			)
			(min_thickness 0.25)
			(keepout
				(tracks allowed)
				(vias not_allowed)
				(pads allowed)
				(copperpour not_allowed)
				(footprints allowed)
			)
			(placement
				(enabled no)
				(sheetname "")
			)
			(fill
				(thermal_gap 0.5)
				(thermal_bridge_width 0.5)
				(island_removal_mode 0)
			)
			(polygon
				(pts
					(xy 108.458 -69.596) (xy 108.966 -69.596) (xy 108.966 -69.215) (xy 108.458 -69.215)
				)
			)
		)
		(zone
			(layer "F.Cu")
			(hatch none 0.5)
			(connect_pads
				(clearance 0)
			)
			(min_thickness 0.25)
			(keepout
				(tracks not_allowed)
				(vias allowed)
				(pads allowed)
				(copperpour not_allowed)
				(footprints allowed)
			)
			(placement
				(enabled no)
				(sheetname "")
			)
			(fill
				(thermal_gap 0.5)
				(thermal_bridge_width 0.5)
				(island_removal_mode 0)
			)
			(polygon
				(pts
					(xy 108.458 -69.215) (xy 108.966 -69.215) (xy 108.966 -69.596) (xy 108.458 -69.596)
				)
			)
		)
	)
)
